# T6G (Grand Teton) — schematic netlist excerpt (pin names and nets, part order shuffled) for the footprints in the layout excerpt that follows; sources: Cadence DE-HDL packaged netlist, KiCad conversion of 04192023_DAF0TMB3IC0_F0TG_MB_C_brd_V02_OCP.brd

PC74  Q_CAP  0.1UF 25V 10% X7R  pkg 0402  page 200 : A = PVDDCR_CPU1_P0_VINSEN ; B = GND
C28  Q_CAP  10UF 6.3V 20% X6S  pkg C0402  page 183 : A = P3V3_9ZXL045_P1_VDD ; B = GND

(kicad_pcb
	(version 20260206)
	(generator "pcbnew")
	(generator_version "10.0")
	(general
		(thickness 1.6)
		(legacy_teardrops no)
	)
	(paper "A4")
	(title_block
		(title "04192023_DAF0TMB3IC0_F0TG_MB_C_brd_V02_OCP.brd")
		(comment 1 "Grand Teton / footprints 1052-1053 of 8354")
	)
	(layers
		(0 "F.Cu" signal "TOP")
		(4 "In1.Cu" signal "GND")
		(6 "In2.Cu" signal "IN1")
		(8 "In3.Cu" signal "GND1")
		(10 "In4.Cu" signal "IN2")
		(12 "In5.Cu" signal "GND2")
		(14 "In6.Cu" signal "IN3")
		(16 "In7.Cu" signal "GND3")
		(18 "In8.Cu" signal "VCC")
		(20 "In9.Cu" signal "VCC1")
		(22 "In10.Cu" signal "GND4")
		(24 "In11.Cu" signal "IN4")
		(26 "In12.Cu" signal "GND5")
		(28 "In13.Cu" signal "IN5")
		(30 "In14.Cu" signal "GND6")
		(32 "In15.Cu" signal "IN6")
		(34 "In16.Cu" signal "GND7")
		(2 "B.Cu" signal "BOTTOM")
		(9 "F.Adhes" user "F.Adhesive")
		(11 "B.Adhes" user "B.Adhesive")
		(13 "F.Paste" user "Package Geometry/Pastemask Top")
		(15 "B.Paste" user "Package Geometry/Pastemask Bottom")
		(5 "F.SilkS" user "Ref Des/Silkscreen Top")
		(7 "B.SilkS" user "Ref Des/Silkscreen Bottom")
		(1 "F.Mask" user "Board Geometry/Soldermask Top")
		(3 "B.Mask" user "Board Geometry/Soldermask Bottom")
		(17 "Dwgs.User" user "User.Drawings")
		(19 "Cmts.User" user "User.Comments")
		(21 "Eco1.User" user "User.Eco1")
		(23 "Eco2.User" user "User.Eco2")
		(25 "Edge.Cuts" user "Board Geometry/Outline")
		(27 "Margin" user)
		(31 "F.CrtYd" user "Package Geometry/Place Bound Top")
		(29 "B.CrtYd" user "Package Geometry/Place Bound Bottom")
		(35 "F.Fab" user "Ref Des/Assembly Top")
		(33 "B.Fab" user "Ref Des/Assembly Bottom")
	)
	(footprint ""
		(layer "F.Cu")
		(at 100.48367 -409.199588 180)
		(property "Reference" "C28"
			(at 0 0 180)
			(layer "F.SilkS")
			(hide yes)
			(effects
				(font
					(size 1.27 1.27)
				)
			)
		)
		(property "Value" ""
			(at 0 0 180)
			(layer "F.Fab")
			(effects
				(font
					(size 1.27 1.27)
				)
			)
		)
		(duplicate_pad_numbers_are_jumpers no)
		(fp_line
			(start 0.7874 0.4064)
			(end -0.7874 0.4064)
			(stroke
				(width 0.1524)
				(type default)
			)
			(layer "F.SilkS")
		)
		(fp_line
			(start 0.7874 -0.4064)
			(end 0.7874 0.4064)
			(stroke
				(width 0.1524)
				(type default)
			)
			(layer "F.SilkS")
		)
		(fp_line
			(start -0.7874 0.4064)
			(end -0.7874 -0.4064)
			(stroke
				(width 0.1524)
				(type default)
			)
			(layer "F.SilkS")
		)
		(fp_line
			(start -0.7874 -0.4064)
			(end 0.7874 -0.4064)
			(stroke
				(width 0.1524)
				(type default)
			)
			(layer "F.SilkS")
		)
		(fp_line
			(start 0.67945 0.3048)
			(end 0.120396 0.3048)
			(stroke
				(width 0.1)
				(type default)
			)
			(layer "F.Fab")
		)
		(fp_line
			(start 0.67945 -0.3048)
			(end 0.67945 0.3048)
			(stroke
				(width 0.1)
				(type default)
			)
			(layer "F.Fab")
		)
		(fp_line
			(start 0.12065 -0.2794)
			(end 0.12065 -0.3048)
			(stroke
				(width 0.1)
				(type default)
			)
			(layer "F.Fab")
		)
		(fp_line
			(start 0.12065 -0.3048)
			(end 0.67945 -0.3048)
			(stroke
				(width 0.1)
				(type default)
			)
			(layer "F.Fab")
		)
		(fp_line
			(start 0.120396 0.3048)
			(end 0.120396 0.2794)
			(stroke
				(width 0.1)
				(type default)
			)
			(layer "F.Fab")
		)
		(fp_line
			(start 0.120396 0.2794)
			(end -0.12065 0.2794)
			(stroke
				(width 0.1)
				(type default)
			)
			(layer "F.Fab")
		)
		(fp_line
			(start -0.12065 0.3048)
			(end -0.67945 0.3048)
			(stroke
				(width 0.1)
				(type default)
			)
			(layer "F.Fab")
		)
		(fp_line
			(start -0.12065 0.2794)
			(end -0.12065 0.3048)
			(stroke
				(width 0.1)
				(type default)
			)
			(layer "F.Fab")
		)
		(fp_line
			(start -0.12065 -0.2794)
			(end 0.12065 -0.2794)
			(stroke
				(width 0.1)
				(type default)
			)
			(layer "F.Fab")
		)
		(fp_line
			(start -0.12065 -0.305054)
			(end -0.12065 -0.2794)
			(stroke
				(width 0.1)
				(type default)
			)
			(layer "F.Fab")
		)
		(fp_line
			(start -0.67945 0.3048)
			(end -0.67945 -0.305054)
			(stroke
				(width 0.1)
				(type default)
			)
			(layer "F.Fab")
		)
		(fp_line
			(start -0.67945 -0.305054)
			(end -0.12065 -0.305054)
			(stroke
				(width 0.1)
				(type default)
			)
			(layer "F.Fab")
		)
		(pad "1" smd circle
			(at -0.40005 0 180)
			(size 0 0)
			(layers "F.Cu" "F.Mask" "F.Paste")
			(net "P3V3_9ZXL045_P1_VDD")
		)
		(pad "2" smd circle
			(at 0.40005 0 180)
			(size 0 0)
			(layers "F.Cu" "F.Mask" "F.Paste")
			(net "GND")
		)
	)
	(footprint ""
		(layer "F.Cu")
		(at 316.23 -362.839 90)
		(property "Reference" "PC74"
			(at 0 0 90)
			(layer "F.SilkS")
			(hide yes)
			(effects
				(font
					(size 1.27 1.27)
				)
			)
		)
		(property "Value" ""
			(at 0 0 90)
			(layer "F.Fab")
			(effects
				(font
					(size 1.27 1.27)
				)
			)
		)
		(duplicate_pad_numbers_are_jumpers no)
		(fp_line
			(start 0.7874 -0.4064)
			(end 0.7874 0.4064)
			(stroke
				(width 0.1524)
				(type default)
			)
			(layer "F.SilkS")
		)
		(fp_line
			(start -0.7874 -0.4064)
			(end 0.7874 -0.4064)
			(stroke
				(width 0.1524)
				(type default)
			)
			(layer "F.SilkS")
		)
		(fp_line
			(start 0.7874 0.4064)
			(end -0.7874 0.4064)
			(stroke
				(width 0.1524)
				(type default)
			)
			(layer "F.SilkS")
		)
		(fp_line
			(start -0.7874 0.4064)
			(end -0.7874 -0.4064)
			(stroke
				(width 0.1524)
				(type default)
			)
			(layer "F.SilkS")
		)
		(fp_line
			(start -0.12065 -0.305054)
			(end -0.12065 -0.2794)
			(stroke
				(width 0.1)
				(type default)
			)
			(layer "F.Fab")
		)
		(fp_line
			(start -0.67945 -0.305054)
			(end -0.12065 -0.305054)
			(stroke
				(width 0.1)
				(type default)
			)
			(layer "F.Fab")
		)
		(fp_line
			(start 0.67945 -0.3048)
			(end 0.67945 0.3048)
			(stroke
				(width 0.1)
				(type default)
			)
			(layer "F.Fab")
		)
		(fp_line
			(start 0.12065 -0.3048)
			(end 0.67945 -0.3048)
			(stroke
				(width 0.1)
				(type default)
			)
			(layer "F.Fab")
		)
		(fp_line
			(start 0.12065 -0.2794)
			(end 0.12065 -0.3048)
			(stroke
				(width 0.1)
				(type default)
			)
			(layer "F.Fab")
		)
		(fp_line
			(start -0.12065 -0.2794)
			(end 0.12065 -0.2794)
			(stroke
				(width 0.1)
				(type default)
			)
			(layer "F.Fab")
		)
		(fp_line
			(start 0.120396 0.2794)
			(end -0.12065 0.2794)
			(stroke
				(width 0.1)
				(type default)
			)
			(layer "F.Fab")
		)
		(fp_line
			(start -0.12065 0.2794)
			(end -0.12065 0.3048)
			(stroke
				(width 0.1)
				(type default)
			)
			(layer "F.Fab")
		)
		(fp_line
			(start 0.67945 0.3048)
			(end 0.120396 0.3048)
			(stroke
				(width 0.1)
				(type default)
			)
			(layer "F.Fab")
		)
		(fp_line
			(start 0.120396 0.3048)
			(end 0.120396 0.2794)
			(stroke
				(width 0.1)
				(type default)
			)
			(layer "F.Fab")
		)
		(fp_line
			(start -0.12065 0.3048)
			(end -0.67945 0.3048)
			(stroke
				(width 0.1)
				(type default)
			)
			(layer "F.Fab")
		)
		(fp_line
			(start -0.67945 0.3048)
			(end -0.67945 -0.305054)
			(stroke
				(width 0.1)
				(type default)
			)
			(layer "F.Fab")
		)
		(pad "1" smd circle
			(at -0.40005 0 90)
			(size 0 0)
			(layers "F.Cu" "F.Mask" "F.Paste")
			(net "PVDDCR_CPU1_P0_VINSEN")
		)
		(pad "2" smd circle
			(at 0.40005 0 90)
			(size 0 0)
			(layers "F.Cu" "F.Mask" "F.Paste")
			(net "GND")
		)
	)
)
